# S9S_MB_2U (Grand Teton) — schematic netlist excerpt (pin names and nets, part order shuffled) for the footprints in the layout excerpt that follows; sources: Cadence DE-HDL packaged netlist, KiCad conversion of 03242023_DA0F0TMBIJ0_F0T_Motherboard_J_brd_V01_OCP.brd

R3652  Q_RES  0 5% CHIP  pkg 0402LF  page 152 : A = USB2_P0_R_DN ; B = USB2_HOST_BMC_B_DN
R1317  Q_RES  1K 1% CHIP  pkg 0402LF  page 201 : A = P1V05_PCH_AUX ; B = PU_BIOS_RCVR_BOOT

(kicad_pcb
	(version 20260206)
	(generator "pcbnew")
	(generator_version "10.0")
	(general
		(thickness 1.6)
		(legacy_teardrops no)
	)
	(paper "A4")
	(title_block
		(title "03242023_DA0F0TMBIJ0_F0T_Motherboard_J_brd_V01_OCP.brd")
		(comment 1 "Grand Teton / footprints 819-820 of 6105")
	)
	(layers
		(0 "F.Cu" signal "TOP")
		(4 "In1.Cu" signal "GND")
		(6 "In2.Cu" signal "IN1")
		(8 "In3.Cu" signal "GND1")
		(10 "In4.Cu" signal "IN2")
		(12 "In5.Cu" signal "GND2")
		(14 "In6.Cu" signal "IN3")
		(16 "In7.Cu" signal "GND3")
		(18 "In8.Cu" signal "VCC")
		(20 "In9.Cu" signal "VCC1")
		(22 "In10.Cu" signal "GND4")
		(24 "In11.Cu" signal "IN4")
		(26 "In12.Cu" signal "GND5")
		(28 "In13.Cu" signal "IN5")
		(30 "In14.Cu" signal "GND6")
		(32 "In15.Cu" signal "IN6")
		(34 "In16.Cu" signal "GND7")
		(2 "B.Cu" signal "BOTTOM")
		(9 "F.Adhes" user "F.Adhesive")
		(11 "B.Adhes" user "B.Adhesive")
		(13 "F.Paste" user "Package Geometry/Pastemask Top")
		(15 "B.Paste" user "Package Geometry/Pastemask Bottom")
		(5 "F.SilkS" user "Ref Des/Silkscreen Top")
		(7 "B.SilkS" user "Ref Des/Silkscreen Bottom")
		(1 "F.Mask" user "Board Geometry/Soldermask Top")
		(3 "B.Mask" user "Board Geometry/Soldermask Bottom")
		(17 "Dwgs.User" user "User.Drawings")
		(19 "Cmts.User" user "User.Comments")
		(21 "Eco1.User" user "User.Eco1")
		(23 "Eco2.User" user "User.Eco2")
		(25 "Edge.Cuts" user "Board Geometry/Outline")
		(27 "Margin" user)
		(31 "F.CrtYd" user "Package Geometry/Place Bound Top")
		(29 "B.CrtYd" user "Package Geometry/Place Bound Bottom")
		(35 "F.Fab" user "Ref Des/Assembly Top")
		(33 "B.Fab" user "Ref Des/Assembly Bottom")
	)
	(footprint ""
		(layer "F.Cu")
		(at 435.17312 -42.140886 180)
		(property "Reference" "R1317"
			(at 0 0 180)
			(layer "F.SilkS")
			(hide yes)
			(effects
				(font
					(size 1.27 1.27)
				)
			)
		)
		(property "Value" ""
			(at 0 0 180)
			(layer "F.Fab")
			(effects
				(font
					(size 1.27 1.27)
				)
			)
		)
		(duplicate_pad_numbers_are_jumpers no)
		(fp_line
			(start 0.7874 0.4064)
			(end -0.7874 0.4064)
			(stroke
				(width 0.1524)
				(type default)
			)
			(layer "F.SilkS")
		)
		(fp_line
			(start 0.7874 -0.4064)
			(end 0.7874 0.4064)
			(stroke
				(width 0.1524)
				(type default)
			)
			(layer "F.SilkS")
		)
		(fp_line
			(start -0.7874 0.4064)
			(end -0.7874 -0.4064)
			(stroke
				(width 0.1524)
				(type default)
			)
			(layer "F.SilkS")
		)
		(fp_line
			(start -0.7874 -0.4064)
			(end 0.7874 -0.4064)
			(stroke
				(width 0.1524)
				(type default)
			)
			(layer "F.SilkS")
		)
		(fp_line
			(start 0.67945 0.3048)
			(end 0.120396 0.3048)
			(stroke
				(width 0.1)
				(type default)
			)
			(layer "F.Fab")
		)
		(fp_line
			(start 0.67945 -0.3048)
			(end 0.67945 0.3048)
			(stroke
				(width 0.1)
				(type default)
			)
			(layer "F.Fab")
		)
		(fp_line
			(start 0.12065 -0.2794)
			(end 0.12065 -0.3048)
			(stroke
				(width 0.1)
				(type default)
			)
			(layer "F.Fab")
		)
		(fp_line
			(start 0.12065 -0.3048)
			(end 0.67945 -0.3048)
			(stroke
				(width 0.1)
				(type default)
			)
			(layer "F.Fab")
		)
		(fp_line
			(start 0.120396 0.3048)
			(end 0.120396 0.2794)
			(stroke
				(width 0.1)
				(type default)
			)
			(layer "F.Fab")
		)
		(fp_line
			(start 0.120396 0.2794)
			(end -0.12065 0.2794)
			(stroke
				(width 0.1)
				(type default)
			)
			(layer "F.Fab")
		)
		(fp_line
			(start -0.12065 0.3048)
			(end -0.67945 0.3048)
			(stroke
				(width 0.1)
				(type default)
			)
			(layer "F.Fab")
		)
		(fp_line
			(start -0.12065 0.2794)
			(end -0.12065 0.3048)
			(stroke
				(width 0.1)
				(type default)
			)
			(layer "F.Fab")
		)
		(fp_line
			(start -0.12065 -0.2794)
			(end 0.12065 -0.2794)
			(stroke
				(width 0.1)
				(type default)
			)
			(layer "F.Fab")
		)
		(fp_line
			(start -0.12065 -0.305054)
			(end -0.12065 -0.2794)
			(stroke
				(width 0.1)
				(type default)
			)
			(layer "F.Fab")
		)
		(fp_line
			(start -0.67945 0.3048)
			(end -0.67945 -0.305054)
			(stroke
				(width 0.1)
				(type default)
			)
			(layer "F.Fab")
		)
		(fp_line
			(start -0.67945 -0.305054)
			(end -0.12065 -0.305054)
			(stroke
				(width 0.1)
				(type default)
			)
			(layer "F.Fab")
		)
		(pad "1" smd circle
			(at -0.40005 0 180)
			(size 0 0)
			(layers "F.Cu" "F.Mask" "F.Paste")
			(net "P1V05_PCH_AUX")
		)
		(pad "2" smd circle
			(at 0.40005 0 180)
			(size 0 0)
			(layers "F.Cu" "F.Mask" "F.Paste")
			(net "PU_BIOS_RCVR_BOOT")
		)
	)
	(footprint ""
		(layer "F.Cu")
		(at 16.645382 -104.76611 90)
		(property "Reference" "R3652"
			(at 0 0 90)
			(layer "F.SilkS")
			(hide yes)
			(effects
				(font
					(size 1.27 1.27)
				)
			)
		)
		(property "Value" ""
			(at 0 0 90)
			(layer "F.Fab")
			(effects
				(font
					(size 1.27 1.27)
				)
			)
		)
		(duplicate_pad_numbers_are_jumpers no)
		(fp_line
			(start 0.7874 -0.4064)
			(end 0.7874 0.4064)
			(stroke
				(width 0.1524)
				(type default)
			)
			(layer "F.SilkS")
		)
		(fp_line
			(start -0.7874 -0.4064)
			(end 0.00127 -0.4064)
			(stroke
				(width 0.1524)
				(type default)
			)
			(layer "F.SilkS")
		)
		(fp_line
			(start 0.01905 0.4064)
			(end -0.7874 0.4064)
			(stroke
				(width 0.1524)
				(type default)
			)
			(layer "F.SilkS")
		)
		(fp_line
			(start -0.12065 -0.305054)
			(end -0.12065 -0.2794)
			(stroke
				(width 0.1)
				(type default)
			)
			(layer "F.Fab")
		)
		(fp_line
			(start -0.67945 -0.305054)
			(end -0.12065 -0.305054)
			(stroke
				(width 0.1)
				(type default)
			)
			(layer "F.Fab")
		)
		(fp_line
			(start 0.67945 -0.3048)
			(end 0.67945 0.3048)
			(stroke
				(width 0.1)
				(type default)
			)
			(layer "F.Fab")
		)
		(fp_line
			(start 0.12065 -0.3048)
			(end 0.67945 -0.3048)
			(stroke
				(width 0.1)
				(type default)
			)
			(layer "F.Fab")
		)
		(fp_line
			(start 0.12065 -0.2794)
			(end 0.12065 -0.3048)
			(stroke
				(width 0.1)
				(type default)
			)
			(layer "F.Fab")
		)
		(fp_line
			(start -0.12065 -0.2794)
			(end 0.12065 -0.2794)
			(stroke
				(width 0.1)
				(type default)
			)
			(layer "F.Fab")
		)
		(fp_line
			(start 0.120396 0.2794)
			(end -0.12065 0.2794)
			(stroke
				(width 0.1)
				(type default)
			)
			(layer "F.Fab")
		)
		(fp_line
			(start -0.12065 0.2794)
			(end -0.12065 0.3048)
			(stroke
				(width 0.1)
				(type default)
			)
			(layer "F.Fab")
		)
		(fp_line
			(start 0.67945 0.3048)
			(end 0.120396 0.3048)
			(stroke
				(width 0.1)
				(type default)
			)
			(layer "F.Fab")
		)
		(fp_line
			(start 0.120396 0.3048)
			(end 0.120396 0.2794)
			(stroke
				(width 0.1)
				(type default)
			)
			(layer "F.Fab")
		)
		(fp_line
			(start -0.12065 0.3048)
			(end -0.67945 0.3048)
			(stroke
				(width 0.1)
				(type default)
			)
			(layer "F.Fab")
		)
		(fp_line
			(start -0.67945 0.3048)
			(end -0.67945 -0.305054)
			(stroke
				(width 0.1)
				(type default)
			)
			(layer "F.Fab")
		)
		(pad "1" smd rect
			(at -0.40005 0 270)
			(size 0.4572 0.508)
			(layers "F.Cu" "F.Mask" "F.Paste")
			(net "USB2_P0_R_DN")
		)
		(pad "2" smd rect
			(at 0.40005 0 270)
			(size 0.4572 0.508)
			(layers "F.Cu" "F.Mask" "F.Paste")
			(net "USB2_HOST_BMC_B_DN")
		)
	)
)
